(kicad_pcb
	(version 20221018)
	(generator pcbnew)
	(general
    (thickness 1.518)
  )
	(paper "A4")
	(title_block
    (title "Kria K26 Devboard")
    (date "2024-03-26")
    (rev "1.2.5")
    (comment 1 "www.antmicro.com")
    (comment 2 "Antmicro Ltd.")
		(comment 9 "footprints 416-427 of 660")
	)
	(layers
    (0 "F.Cu" mixed)
    (1 "In1.Cu" power)
    (2 "In2.Cu" mixed)
    (3 "In3.Cu" power)
    (4 "In4.Cu" mixed)
    (5 "In5.Cu" power)
    (6 "In6.Cu" mixed)
    (31 "B.Cu" power)
    (32 "B.Adhes" user "B.Adhesive")
    (33 "F.Adhes" user "F.Adhesive")
    (34 "B.Paste" user)
    (35 "F.Paste" user)
    (36 "B.SilkS" user "B.Silkscreen")
    (37 "F.SilkS" user "F.Silkscreen")
    (38 "B.Mask" user)
    (39 "F.Mask" user)
    (40 "Dwgs.User" user "User.Drawings")
    (41 "Cmts.User" user "User.Comments")
    (42 "Eco1.User" user "User.Eco1")
    (43 "Eco2.User" user "User.Eco2")
    (44 "Edge.Cuts" user)
    (45 "Margin" user)
    (46 "B.CrtYd" user "B.Courtyard")
    (47 "F.CrtYd" user "F.Courtyard")
    (48 "B.Fab" user)
    (49 "F.Fab" user)
  )
	(footprint "kria-k26-devboard-footprints:TP_SMD_0.75mm" (layer "F.Cu")
    (at 81.55 108.8492 180)
    (property "Author" "Antmicro")
    (property "License" "Apache-2.0")
    (property "MPN" "")
    (property "Manufacturer" "")
    (property "Sheetfile" "k26_som.kicad_sch")
    (property "Sheetname" "Xilinx K26 SOM")
    (property "ki_description" "Test Point 0.75mm")
    (attr exclude_from_pos_files)
    (fp_text reference "TP55" (at 3.36 -0.2808 180) (layer "F.SilkS")
        (effects (font (size 0.7 0.7) (thickness 0.15)) (justify left bottom))
    )
    (fp_text value "TP_0.75mm_SMD" (at 0 1.2 180) (layer "F.Fab") hide
        (effects (font (size 0.7 0.7) (thickness 0.15)) (justify left bottom))
    )
    (fp_text user "${REFERENCE}" (at -0.4 2.7 180) (layer "F.Fab") hide
        (effects (font (size 0.7 0.7) (thickness 0.15)) (justify left bottom))
    )
    (fp_text user "License: Apache-2.0" (at -0.4 5.101 180) (layer "F.Fab") hide
        (effects (font (size 0.7 0.7) (thickness 0.15)) (justify left bottom))
    )
    (fp_text user "Author: Antmicro" (at -0.4 3.901 180) (layer "F.Fab") hide
        (effects (font (size 0.7 0.7) (thickness 0.15)) (justify left bottom))
    )
    (pad "1" smd circle (at 0 0 180) (size 0.75 0.75) (layers "F.Cu" "F.Mask")
      (net 473 "/Xilinx K26 SOM/PWRGD_FPD_M2C") (pinfunction "1") (pintype "passive"))
  )
	(footprint "kria-k26-devboard-footprints:TP_SMD_0.75mm" (layer "F.Cu")
    (at 139.3 139.3 180)
    (property "Author" "Antmicro")
    (property "License" "Apache-2.0")
    (property "MPN" "")
    (property "Manufacturer" "")
    (property "Sheetfile" "sd-3-card.kicad_sch")
    (property "Sheetname" "SD 3.0 card")
    (property "ki_description" "Test Point 0.75mm")
    (attr exclude_from_pos_files)
    (fp_text reference "TP60" (at 1.23 -1.22 180) (layer "F.SilkS")
        (effects (font (size 0.7 0.7) (thickness 0.15)) (justify left bottom))
    )
    (fp_text value "TP_0.75mm_SMD" (at 0 1.2 180) (layer "F.Fab") hide
        (effects (font (size 0.7 0.7) (thickness 0.15)) (justify left bottom))
    )
    (fp_text user "Author: Antmicro" (at -0.4 3.901 180) (layer "F.Fab") hide
        (effects (font (size 0.7 0.7) (thickness 0.15)) (justify left bottom))
    )
    (fp_text user "License: Apache-2.0" (at -0.4 5.101 180) (layer "F.Fab") hide
        (effects (font (size 0.7 0.7) (thickness 0.15)) (justify left bottom))
    )
    (fp_text user "${REFERENCE}" (at -0.4 2.7 180) (layer "F.Fab") hide
        (effects (font (size 0.7 0.7) (thickness 0.15)) (justify left bottom))
    )
    (pad "1" smd circle (at 0 0 180) (size 0.75 0.75) (layers "F.Cu" "F.Mask")
      (net 695 "Net-(U6-ST)") (pinfunction "1") (pintype "passive"))
  )
	(footprint "kria-k26-devboard-footprints:C_0402_1005Metric" (layer "F.Cu")
    (at 166.885 75.9)
    (descr "Capacitor SMD 0402")
    (tags "capacitor SMD 0402")
    (property "Author" "Antmicro")
    (property "Dielectric" "X5R")
    (property "License" "Apache-2.0")
    (property "MPN" "GRM155R61H104KE14D")
    (property "Manufacturer" "Murata")
    (property "Sheetfile" "eth.kicad_sch")
    (property "Sheetname" "Ethernet")
    (property "Val" "100n")
    (property "Voltage" "50V")
    (property "ki_description" " ")
    (attr smd)
    (fp_text reference "C239" (at -1.185 -0.58) (layer "F.SilkS")
        (effects (font (size 0.7 0.7) (thickness 0.15)) (justify left bottom))
    )
    (fp_text value "C_100n_0402" (at 0 1.4) (layer "F.Fab") hide
        (effects (font (size 0.7 0.7) (thickness 0.15)) (justify left bottom))
    )
    (fp_text user "${REFERENCE}" (at -0.932 3.168) (layer "F.Fab") hide
        (effects (font (size 0.7 0.7) (thickness 0.15)) (justify left bottom))
    )
    (fp_text user "Author: Antmicro" (at -0.932 4.17) (layer "F.Fab") hide
        (effects (font (size 0.7 0.7) (thickness 0.15)) (justify left bottom))
    )
    (fp_text user "License: Apache-2.0" (at -0.932 5.17) (layer "F.Fab") hide
        (effects (font (size 0.7 0.7) (thickness 0.15)) (justify left bottom))
    )
    (fp_rect (start -0.94 -0.47) (end 0.94 0.47)
      (stroke (width 0.05) (type solid)) (fill none) (layer "F.CrtYd"))
    (fp_rect (start -0.499 -0.249) (end 0.499 0.249)
      (stroke (width 0.15) (type solid)) (fill none) (layer "F.Fab"))
    (pad "1" smd roundrect (at -0.484 0) (size 0.59 0.64) (layers "F.Cu" "F.Paste" "F.Mask") (roundrect_rratio 0.25)
      (net 332 "Net-(J5-P4)") (pintype "passive"))
    (pad "2" smd roundrect (at 0.484 0) (size 0.59 0.64) (layers "F.Cu" "F.Paste" "F.Mask") (roundrect_rratio 0.25)
      (net 1 "GND") (pintype "passive"))
  )
	(footprint "kria-k26-devboard-footprints:C_0603_1608Metric" (layer "F.Cu")
    (at 79.115 88.3 180)
    (descr "Capacitor SMD 0603")
    (tags "capacitor 0603")
    (property "Author" "Antmicro")
    (property "License" "Apache-2.0")
    (property "MPN" "GRM188R61A106KE69D")
    (property "Manufacturer" "Murata")
    (property "Sheetfile" "camera.kicad_sch")
    (property "Sheetname" "Camera interface")
    (property "Val" "10u")
    (property "Voltage" "")
    (property "ki_description" " ")
    (attr smd)
    (fp_text reference "C245" (at 4.054 -0.375 180) (layer "F.SilkS")
        (effects (font (size 0.7 0.7) (thickness 0.15)) (justify left bottom))
    )
    (fp_text value "C_10u_0603" (at 0 1.6 180) (layer "F.Fab") hide
        (effects (font (size 0.7 0.7) (thickness 0.15)) (justify left bottom))
    )
    (fp_text user "License: Apache-2.0" (at -1.682 5.895 180) (layer "F.Fab") hide
        (effects (font (size 0.7 0.7) (thickness 0.15)) (justify left bottom))
    )
    (fp_text user "Author: Antmicro" (at -1.682 4.894 180) (layer "F.Fab") hide
        (effects (font (size 0.7 0.7) (thickness 0.15)) (justify left bottom))
    )
    (fp_text user "${REFERENCE}" (at -1.682 3.895 180) (layer "F.Fab") hide
        (effects (font (size 0.7 0.7) (thickness 0.15)) (justify left bottom))
    )
    (fp_line (start -0.3 -0.3) (end 0.3 -0.3)
      (stroke (width 0.15) (type solid)) (layer "F.SilkS"))
    (fp_line (start -0.3 0.3) (end 0.3 0.3)
      (stroke (width 0.15) (type solid)) (layer "F.SilkS"))
    (fp_rect (start -1.24 -0.7) (end 1.24 0.7)
      (stroke (width 0.05) (type solid)) (fill none) (layer "F.CrtYd"))
    (fp_rect (start -0.8 -0.4) (end 0.8 0.4)
      (stroke (width 0.15) (type solid)) (fill none) (layer "F.Fab"))
    (pad "1" smd roundrect (at -0.7 0 180) (size 0.6 0.8) (layers "F.Cu" "F.Paste" "F.Mask") (roundrect_rratio 0.2)
      (net 8 "SOM_5V0") (pintype "passive"))
    (pad "2" smd roundrect (at 0.7 0 180) (size 0.6 0.8) (layers "F.Cu" "F.Paste" "F.Mask") (roundrect_rratio 0.2)
      (net 1 "GND") (pintype "passive"))
  )
	(footprint "kria-k26-devboard-footprints:C_0402_1005Metric" (layer "F.Cu")
    (at 83.9 147.6)
    (descr "Capacitor SMD 0402")
    (tags "capacitor SMD 0402")
    (property "Author" "Antmicro")
    (property "Dielectric" "X5R")
    (property "License" "Apache-2.0")
    (property "MPN" "GRM155R61H104KE14D")
    (property "Manufacturer" "Murata")
    (property "Sheetfile" "k26_som.kicad_sch")
    (property "Sheetname" "Xilinx K26 SOM")
    (property "Val" "100n")
    (property "Voltage" "50V")
    (property "ki_description" " ")
    (attr smd)
    (fp_text reference "C241" (at -1.2 -0.55) (layer "F.SilkS")
        (effects (font (size 0.7 0.7) (thickness 0.15)) (justify left bottom))
    )
    (fp_text value "C_100n_0402" (at 0 1.4) (layer "F.Fab") hide
        (effects (font (size 0.7 0.7) (thickness 0.15)) (justify left bottom))
    )
    (fp_text user "Author: Antmicro" (at -0.932 4.17) (layer "F.Fab") hide
        (effects (font (size 0.7 0.7) (thickness 0.15)) (justify left bottom))
    )
    (fp_text user "License: Apache-2.0" (at -0.932 5.17) (layer "F.Fab") hide
        (effects (font (size 0.7 0.7) (thickness 0.15)) (justify left bottom))
    )
    (fp_text user "${REFERENCE}" (at -0.932 3.168) (layer "F.Fab") hide
        (effects (font (size 0.7 0.7) (thickness 0.15)) (justify left bottom))
    )
    (fp_rect (start -0.94 -0.47) (end 0.94 0.47)
      (stroke (width 0.05) (type solid)) (fill none) (layer "F.CrtYd"))
    (fp_rect (start -0.499 -0.249) (end 0.499 0.249)
      (stroke (width 0.15) (type solid)) (fill none) (layer "F.Fab"))
    (pad "1" smd roundrect (at -0.484 0) (size 0.59 0.64) (layers "F.Cu" "F.Paste" "F.Mask") (roundrect_rratio 0.25)
      (net 467 "/Xilinx K26 SOM/MIO12_FWUEN_C2M_L") (pintype "passive"))
    (pad "2" smd roundrect (at 0.484 0) (size 0.59 0.64) (layers "F.Cu" "F.Paste" "F.Mask") (roundrect_rratio 0.25)
      (net 1 "GND") (pintype "passive"))
  )
	(footprint "kria-k26-devboard-footprints:C_0402_1005Metric" (layer "F.Cu")
    (at 164.405 75.9)
    (descr "Capacitor SMD 0402")
    (tags "capacitor SMD 0402")
    (property "Author" "Antmicro")
    (property "Dielectric" "X5R")
    (property "License" "Apache-2.0")
    (property "MPN" "GRM155R61H104KE14D")
    (property "Manufacturer" "Murata")
    (property "Sheetfile" "eth.kicad_sch")
    (property "Sheetname" "Ethernet")
    (property "Val" "100n")
    (property "Voltage" "50V")
    (property "ki_description" " ")
    (attr smd)
    (fp_text reference "C240" (at -1.495 -0.59) (layer "F.SilkS")
        (effects (font (size 0.7 0.7) (thickness 0.15)) (justify left bottom))
    )
    (fp_text value "C_100n_0402" (at 0 1.4) (layer "F.Fab") hide
        (effects (font (size 0.7 0.7) (thickness 0.15)) (justify left bottom))
    )
    (fp_text user "License: Apache-2.0" (at -0.932 5.17) (layer "F.Fab") hide
        (effects (font (size 0.7 0.7) (thickness 0.15)) (justify left bottom))
    )
    (fp_text user "Author: Antmicro" (at -0.932 4.17) (layer "F.Fab") hide
        (effects (font (size 0.7 0.7) (thickness 0.15)) (justify left bottom))
    )
    (fp_text user "${REFERENCE}" (at -0.932 3.168) (layer "F.Fab") hide
        (effects (font (size 0.7 0.7) (thickness 0.15)) (justify left bottom))
    )
    (fp_rect (start -0.94 -0.47) (end 0.94 0.47)
      (stroke (width 0.05) (type solid)) (fill none) (layer "F.CrtYd"))
    (fp_rect (start -0.499 -0.249) (end 0.499 0.249)
      (stroke (width 0.15) (type solid)) (fill none) (layer "F.Fab"))
    (pad "1" smd roundrect (at -0.484 0) (size 0.59 0.64) (layers "F.Cu" "F.Paste" "F.Mask") (roundrect_rratio 0.25)
      (net 333 "Net-(J5-P5)") (pintype "passive"))
    (pad "2" smd roundrect (at 0.484 0) (size 0.59 0.64) (layers "F.Cu" "F.Paste" "F.Mask") (roundrect_rratio 0.25)
      (net 1 "GND") (pintype "passive"))
  )
	(footprint "kria-k26-devboard-footprints:TP_SMD_0.75mm" (layer "F.Cu")
    (at 82.229289 101.870711 180)
    (property "Author" "Antmicro")
    (property "License" "Apache-2.0")
    (property "MPN" "")
    (property "Manufacturer" "")
    (property "Sheetfile" "k26_som.kicad_sch")
    (property "Sheetname" "Xilinx K26 SOM")
    (property "ki_description" "Test Point 0.75mm")
    (attr exclude_from_pos_files)
    (fp_text reference "TP59" (at 4.029289 -0.27 180) (layer "F.SilkS")
        (effects (font (size 0.7 0.7) (thickness 0.15)) (justify left bottom))
    )
    (fp_text value "TP_0.75mm_SMD" (at 0 1.2 180) (layer "F.Fab") hide
        (effects (font (size 0.7 0.7) (thickness 0.15)) (justify left bottom))
    )
    (fp_text user "Author: Antmicro" (at -0.4 3.901 180) (layer "F.Fab") hide
        (effects (font (size 0.7 0.7) (thickness 0.15)) (justify left bottom))
    )
    (fp_text user "${REFERENCE}" (at -0.4 2.7 180) (layer "F.Fab") hide
        (effects (font (size 0.7 0.7) (thickness 0.15)) (justify left bottom))
    )
    (fp_text user "License: Apache-2.0" (at -0.4 5.101 180) (layer "F.Fab") hide
        (effects (font (size 0.7 0.7) (thickness 0.15)) (justify left bottom))
    )
    (pad "1" smd circle (at 0 0 180) (size 0.75 0.75) (layers "F.Cu" "F.Mask")
      (net 458 "/Xilinx K26 SOM/MIO35_WD_OUT") (pinfunction "1") (pintype "passive"))
  )
	(footprint "kria-k26-devboard-footprints:R_0402_1005Metric" (layer "F.Cu")
    (at 111.94 92.24 180)
    (descr "Resistor SMD 0402")
    (tags "resistor SMD 0402")
    (property "Author" "Antmicro")
    (property "License" "Apache-2.0")
    (property "MPN" "CR0402-FX-2003GLF")
    (property "Manufacturer" "Bourns")
    (property "Sheetfile" "usb.kicad_sch")
    (property "Sheetname" "USB")
    (property "Tolerance" "1%")
    (property "Val" "200k")
    (property "ki_description" "200k resistor in 0402 package with 1% tolerance")
    (attr smd)
    (fp_text reference "R173" (at 3.705 -0.35 180) (layer "F.SilkS")
        (effects (font (size 0.7 0.7) (thickness 0.15)) (justify left bottom))
    )
    (fp_text value "R_200k_0402" (at 0 1.4 180) (layer "F.Fab") hide
        (effects (font (size 0.7 0.7) (thickness 0.15)) (justify left bottom))
    )
    (fp_text user "License: Apache-2.0" (at -0.95 5.169 180) (layer "F.Fab") hide
        (effects (font (size 0.7 0.7) (thickness 0.15)) (justify left bottom))
    )
    (fp_text user "${REFERENCE}" (at -0.95 3.168 180) (layer "F.Fab") hide
        (effects (font (size 0.7 0.7) (thickness 0.15)) (justify left bottom))
    )
    (fp_text user "Author: Antmicro" (at -0.95 4.169 180) (layer "F.Fab") hide
        (effects (font (size 0.7 0.7) (thickness 0.15)) (justify left bottom))
    )
    (fp_rect (start -0.93 -0.47) (end 0.93 0.47)
      (stroke (width 0.05) (type solid)) (fill none) (layer "F.CrtYd"))
    (fp_rect (start -0.5 -0.25) (end 0.5 0.25)
      (stroke (width 0.15) (type solid)) (fill none) (layer "F.Fab"))
    (pad "1" smd roundrect (at -0.485 0 180) (size 0.59 0.64) (layers "F.Cu" "F.Paste" "F.Mask") (roundrect_rratio 0.25)
      (net 667 "Net-(U17-PF27)") (pintype "passive"))
    (pad "2" smd roundrect (at 0.485 0 180) (size 0.59 0.64) (layers "F.Cu" "F.Paste" "F.Mask") (roundrect_rratio 0.25)
      (net 1 "GND") (pintype "passive"))
  )
	(footprint "kria-k26-devboard-footprints:TP_SMD_0.75mm" (layer "F.Cu")
    (at 82.229289 103.95 180)
    (property "Author" "Antmicro")
    (property "License" "Apache-2.0")
    (property "MPN" "")
    (property "Manufacturer" "")
    (property "Sheetfile" "k26_som.kicad_sch")
    (property "Sheetname" "Xilinx K26 SOM")
    (property "ki_description" "Test Point 0.75mm")
    (attr exclude_from_pos_files)
    (fp_text reference "TP52" (at 4.029289 -0.27 180) (layer "F.SilkS")
        (effects (font (size 0.7 0.7) (thickness 0.15)) (justify left bottom))
    )
    (fp_text value "TP_0.75mm_SMD" (at 0 1.2 180) (layer "F.Fab") hide
        (effects (font (size 0.7 0.7) (thickness 0.15)) (justify left bottom))
    )
    (fp_text user "License: Apache-2.0" (at -0.4 5.101 180) (layer "F.Fab") hide
        (effects (font (size 0.7 0.7) (thickness 0.15)) (justify left bottom))
    )
    (fp_text user "Author: Antmicro" (at -0.4 3.901 180) (layer "F.Fab") hide
        (effects (font (size 0.7 0.7) (thickness 0.15)) (justify left bottom))
    )
    (fp_text user "${REFERENCE}" (at -0.4 2.7 180) (layer "F.Fab") hide
        (effects (font (size 0.7 0.7) (thickness 0.15)) (justify left bottom))
    )
    (pad "1" smd circle (at 0 0 180) (size 0.75 0.75) (layers "F.Cu" "F.Mask")
      (net 455 "/Xilinx K26 SOM/PS_ERROR_OUT_M2C") (pinfunction "1") (pintype "passive"))
  )
	(footprint "kria-k26-devboard-footprints:C_0402_1005Metric" (layer "F.Cu")
    (at 79.425 92.175 180)
    (descr "Capacitor SMD 0402")
    (tags "capacitor SMD 0402")
    (property "Author" "Antmicro")
    (property "Dielectric" "X5R")
    (property "License" "Apache-2.0")
    (property "MPN" "GRM155R61H104KE14D")
    (property "Manufacturer" "Murata")
    (property "Sheetfile" "camera.kicad_sch")
    (property "Sheetname" "Camera interface")
    (property "Val" "100n")
    (property "Voltage" "50V")
    (property "ki_description" " ")
    (attr smd)
    (fp_text reference "C246" (at 3.845 -0.335 180) (layer "F.SilkS")
        (effects (font (size 0.7 0.7) (thickness 0.15)) (justify left bottom))
    )
    (fp_text value "C_100n_0402" (at 0 1.4 180) (layer "F.Fab") hide
        (effects (font (size 0.7 0.7) (thickness 0.15)) (justify left bottom))
    )
    (fp_text user "${REFERENCE}" (at -0.932 3.168 180) (layer "F.Fab") hide
        (effects (font (size 0.7 0.7) (thickness 0.15)) (justify left bottom))
    )
    (fp_text user "Author: Antmicro" (at -0.932 4.17 180) (layer "F.Fab") hide
        (effects (font (size 0.7 0.7) (thickness 0.15)) (justify left bottom))
    )
    (fp_text user "License: Apache-2.0" (at -0.932 5.17 180) (layer "F.Fab") hide
        (effects (font (size 0.7 0.7) (thickness 0.15)) (justify left bottom))
    )
    (fp_rect (start -0.94 -0.47) (end 0.94 0.47)
      (stroke (width 0.05) (type solid)) (fill none) (layer "F.CrtYd"))
    (fp_rect (start -0.499 -0.249) (end 0.499 0.249)
      (stroke (width 0.15) (type solid)) (fill none) (layer "F.Fab"))
    (pad "1" smd roundrect (at -0.484 0 180) (size 0.59 0.64) (layers "F.Cu" "F.Paste" "F.Mask") (roundrect_rratio 0.25)
      (net 20 "PL_3V3") (pintype "passive"))
    (pad "2" smd roundrect (at 0.484 0 180) (size 0.59 0.64) (layers "F.Cu" "F.Paste" "F.Mask") (roundrect_rratio 0.25)
      (net 1 "GND") (pintype "passive"))
  )
	(footprint "kria-k26-devboard-footprints:TP_SMD_0.75mm" (layer "F.Cu")
    (at 153.7492 150.825 -90)
    (property "Author" "Antmicro")
    (property "License" "Apache-2.0")
    (property "MPN" "")
    (property "Manufacturer" "")
    (property "Sheetfile" "debug.kicad_sch")
    (property "Sheetname" "Debug and JTAG")
    (property "ki_description" "Test Point 0.75mm")
    (attr exclude_from_pos_files)
    (fp_text reference "TP63" (at -0.47 -0.4308 -90) (layer "F.SilkS")
        (effects (font (size 0.7 0.7) (thickness 0.15)) (justify left bottom))
    )
    (fp_text value "TP_0.75mm_SMD" (at 0 1.2 -90) (layer "F.Fab") hide
        (effects (font (size 0.7 0.7) (thickness 0.15)) (justify left bottom))
    )
    (fp_text user "${REFERENCE}" (at -0.4 2.7 -90) (layer "F.Fab") hide
        (effects (font (size 0.7 0.7) (thickness 0.15)) (justify left bottom))
    )
    (fp_text user "Author: Antmicro" (at -0.4 3.901 -90) (layer "F.Fab") hide
        (effects (font (size 0.7 0.7) (thickness 0.15)) (justify left bottom))
    )
    (fp_text user "License: Apache-2.0" (at -0.4 5.101 -90) (layer "F.Fab") hide
        (effects (font (size 0.7 0.7) (thickness 0.15)) (justify left bottom))
    )
    (pad "1" smd circle (at 0 0 270) (size 0.75 0.75) (layers "F.Cu" "F.Mask")
      (net 699 "Net-(U40-CDBUS0)") (pinfunction "1") (pintype "passive"))
  )
	(footprint "kria-k26-devboard-footprints:C_0402_1005Metric" (layer "B.Cu")
    (at 120.6 100.288999 90)
    (descr "Capacitor SMD 0402")
    (tags "capacitor SMD 0402")
    (property "Author" "Antmicro")
    (property "Dielectric" "X5R")
    (property "License" "Apache-2.0")
    (property "MPN" "GRM155R61H104KE14D")
    (property "Manufacturer" "Murata")
    (property "Sheetfile" "usb.kicad_sch")
    (property "Sheetname" "USB")
    (property "Val" "100n")
    (property "Voltage" "50V")
    (property "ki_description" " ")
    (attr smd)
    (fp_text reference "C80" (at 0.858999 1.33 270) (layer "B.SilkS")
        (effects (font (size 0.7 0.7) (thickness 0.15)) (justify left bottom mirror))
    )
    (fp_text value "C_100n_0402" (at 0 -1.4 270) (layer "B.Fab") hide
        (effects (font (size 0.7 0.7) (thickness 0.15)) (justify left bottom mirror))
    )
    (fp_text user "License: Apache-2.0" (at -0.932 -5.17 270) (layer "B.Fab") hide
        (effects (font (size 0.7 0.7) (thickness 0.15)) (justify left bottom mirror))
    )
    (fp_text user "${REFERENCE}" (at -0.932 -3.168 270) (layer "B.Fab") hide
        (effects (font (size 0.7 0.7) (thickness 0.15)) (justify left bottom mirror))
    )
    (fp_text user "Author: Antmicro" (at -0.932 -4.17 270) (layer "B.Fab") hide
        (effects (font (size 0.7 0.7) (thickness 0.15)) (justify left bottom mirror))
    )
    (fp_rect (start -0.94 0.47) (end 0.94 -0.47)
      (stroke (width 0.05) (type solid)) (fill none) (layer "B.CrtYd"))
    (fp_rect (start -0.499 0.249) (end 0.499 -0.249)
      (stroke (width 0.15) (type solid)) (fill none) (layer "B.Fab"))
    (pad "1" smd roundrect (at -0.484 0 90) (size 0.59 0.64) (layers "B.Cu" "B.Paste" "B.Mask") (roundrect_rratio 0.25)
      (net 17 "PS_1V8") (pintype "passive"))
    (pad "2" smd roundrect (at 0.484 0 90) (size 0.59 0.64) (layers "B.Cu" "B.Paste" "B.Mask") (roundrect_rratio 0.25)
      (net 1 "GND") (pintype "passive"))
  )
)
